(kicad_pcb
	(version 20241229)
	(generator "pcbnew")
	(generator_version "9.0")
	(general
		(thickness 1.62)
		(legacy_teardrops no)
	)
	(paper "A3")
	(title_block
		(title "COM Express 7 Baseboard")
		(date "2025-02-04")
		(rev "1.1.2")
		(company "Antmicro Ltd")
		(comment 1 "www.antmicro.com")
		(comment 9 "footprints 74-77 of 802")
	)
	(layers
		(0 "F.Cu" signal)
		(4 "In1.Cu" signal)
		(6 "In2.Cu" signal)
		(8 "In3.Cu" signal)
		(10 "In4.Cu" signal)
		(12 "In5.Cu" signal)
		(14 "In6.Cu" signal)
		(2 "B.Cu" signal)
		(9 "F.Adhes" user "F.Adhesive")
		(11 "B.Adhes" user "B.Adhesive")
		(13 "F.Paste" user)
		(15 "B.Paste" user)
		(5 "F.SilkS" user "F.Silkscreen")
		(7 "B.SilkS" user "B.Silkscreen")
		(1 "F.Mask" user)
		(3 "B.Mask" user)
		(17 "Dwgs.User" user "User.Drawings")
		(19 "Cmts.User" user "User.Comments")
		(21 "Eco1.User" user "User.Eco1")
		(23 "Eco2.User" user "User.Eco2")
		(25 "Edge.Cuts" user)
		(27 "Margin" user)
		(31 "F.CrtYd" user "F.Courtyard")
		(29 "B.CrtYd" user "B.Courtyard")
		(35 "F.Fab" user)
		(33 "B.Fab" user)
	)
	(footprint "antmicro-footprints:LED_0603_1608Metric_G"
		(layer "F.Cu")
		(at 195.70861 74.802163 90)
		(descr "LED SMD 0603 Green")
		(tags "LED SMD 0603 Green")
		(property "Reference" "D34"
			(at -1.1 -0.55 90)
			(layer "F.SilkS")
			(effects
				(font
					(size 0.7 0.7)
					(thickness 0.15)
				)
				(justify left bottom)
			)
		)
		(property "Value" "LED_G_0603_LTST-C190GKT"
			(at -0.001 1.599 90)
			(layer "F.Fab")
			(effects
				(font
					(size 0.7 0.7)
					(thickness 0.15)
				)
				(justify left bottom)
			)
		)
		(property "Datasheet" "https://media.digikey.com/pdf/Data%20Sheets/Lite-On%20PDFs/LTST-C190GKT.pdf"
			(at 0 0 90)
			(layer "F.Fab")
			(hide yes)
			(effects
				(font
					(size 1.27 1.27)
					(thickness 0.15)
				)
			)
		)
		(property "Author" "Antmicro"
			(at 270.510773 -120.906447 0)
			(layer "F.Fab")
			(hide yes)
			(effects
				(font
					(size 1 1)
					(thickness 0.15)
				)
			)
		)
		(property "Color" "Green"
			(at 270.510773 -120.906447 0)
			(layer "F.Fab")
			(hide yes)
			(effects
				(font
					(size 1 1)
					(thickness 0.15)
				)
			)
		)
		(property "License" "Apache-2.0"
			(at 270.510773 -120.906447 0)
			(layer "F.Fab")
			(hide yes)
			(effects
				(font
					(size 1 1)
					(thickness 0.15)
				)
			)
		)
		(property "MPN" "LTST-C190GKT"
			(at 270.510773 -120.906447 0)
			(layer "F.Fab")
			(hide yes)
			(effects
				(font
					(size 1 1)
					(thickness 0.15)
				)
			)
		)
		(property "Manufacturer" "Lite-On"
			(at 270.510773 -120.906447 0)
			(layer "F.Fab")
			(hide yes)
			(effects
				(font
					(size 1 1)
					(thickness 0.15)
				)
			)
		)
		(property "Public" "False"
			(at 270.510773 -120.906447 0)
			(layer "F.Fab")
			(hide yes)
			(effects
				(font
					(size 1 1)
					(thickness 0.15)
				)
			)
		)
		(sheetname "Power")
		(sheetfile "power.kicad_sch")
		(attr smd)
		(fp_line
			(start 0.22 -0.35)
			(end -0.22 -0.35)
			(stroke
				(width 0.15)
				(type solid)
			)
			(layer "F.SilkS")
		)
		(fp_line
			(start -1.18 -0.319)
			(end -1.18 0.321)
			(stroke
				(width 0.15)
				(type solid)
			)
			(layer "F.SilkS")
		)
		(fp_line
			(start 0.105328 0.001008)
			(end 0.24 0.001)
			(stroke
				(width 0.1)
				(type solid)
			)
			(layer "F.SilkS")
		)
		(fp_line
			(start -0.094672 0.001008)
			(end 0.105328 -0.198992)
			(stroke
				(width 0.1)
				(type solid)
			)
			(layer "F.SilkS")
		)
		(fp_line
			(start -0.094672 0.001008)
			(end -0.24 0.001008)
			(stroke
				(width 0.1)
				(type solid)
			)
			(layer "F.SilkS")
		)
		(fp_line
			(start 0.105328 0.201008)
			(end 0.105328 -0.198992)
			(stroke
				(width 0.1)
				(type solid)
			)
			(layer "F.SilkS")
		)
		(fp_line
			(start 0.105328 0.201008)
			(end -0.094672 0.001008)
			(stroke
				(width 0.1)
				(type solid)
			)
			(layer "F.SilkS")
		)
		(fp_line
			(start -0.094672 0.201008)
			(end -0.094672 -0.198992)
			(stroke
				(width 0.1)
				(type solid)
			)
			(layer "F.SilkS")
		)
		(fp_line
			(start 0.22 0.35)
			(end -0.22 0.35)
			(stroke
				(width 0.15)
				(type solid)
			)
			(layer "F.SilkS")
		)
		(fp_rect
			(start 1.25 0.65)
			(end -1.25 -0.65)
			(stroke
				(width 0.05)
				(type solid)
			)
			(fill no)
			(layer "F.CrtYd")
		)
		(fp_line
			(start 0.201 -0.202)
			(end -0.101 0)
			(stroke
				(width 0.15)
				(type solid)
			)
			(layer "F.Fab")
		)
		(fp_line
			(start -0.199 -0.202)
			(end -0.199 0.1)
			(stroke
				(width 0.15)
				(type solid)
			)
			(layer "F.Fab")
		)
		(fp_line
			(start 0.599 0)
			(end 0.201 0)
			(stroke
				(width 0.15)
				(type solid)
			)
			(layer "F.Fab")
		)
		(fp_line
			(start 0.201 0)
			(end 0.201 -0.202)
			(stroke
				(width 0.15)
				(type solid)
			)
			(layer "F.Fab")
		)
		(fp_line
			(start -0.101 0)
			(end 0.201 0.2)
			(stroke
				(width 0.15)
				(type solid)
			)
			(layer "F.Fab")
		)
		(fp_line
			(start -0.199 0)
			(end -0.597 0)
			(stroke
				(width 0.15)
				(type solid)
			)
			(layer "F.Fab")
		)
		(fp_line
			(start 0.201 0.2)
			(end 0.201 0)
			(stroke
				(width 0.15)
				(type solid)
			)
			(layer "F.Fab")
		)
		(fp_line
			(start -0.199 0.2)
			(end -0.199 0.1)
			(stroke
				(width 0.15)
				(type solid)
			)
			(layer "F.Fab")
		)
		(fp_rect
			(start 0.848 0.4)
			(end -0.85 -0.402)
			(stroke
				(width 0.15)
				(type solid)
			)
			(fill no)
			(layer "F.Fab")
		)
		(pad "1" smd roundrect
			(at -0.7 0 270)
			(size 0.8 1)
			(layers "F.Cu" "F.Mask" "F.Paste")
			(roundrect_rratio 0.2)
			(net 986 "Net-(D34-C)")
			(pinfunction "C")
			(pintype "passive")
			(teardrops
				(best_length_ratio 0.2)
				(max_length 1)
				(best_width_ratio 0.9)
				(max_width 2)
				(curved_edges yes)
				(filter_ratio 0.9)
				(enabled yes)
				(allow_two_segments yes)
				(prefer_zone_connections yes)
			)
		)
		(pad "2" smd roundrect
			(at 0.7 0 270)
			(size 0.8 1)
			(layers "F.Cu" "F.Mask" "F.Paste")
			(roundrect_rratio 0.2)
			(net 52 "+5V")
			(pinfunction "A")
			(pintype "passive")
			(teardrops
				(best_length_ratio 0.2)
				(max_length 1)
				(best_width_ratio 0.9)
				(max_width 2)
				(curved_edges yes)
				(filter_ratio 0.9)
				(enabled yes)
				(allow_two_segments yes)
				(prefer_zone_connections yes)
			)
		)
	)
	(footprint "antmicro-footprints:C_0402_1005Metric"
		(layer "F.Cu")
		(at 124.84 141.86)
		(descr "Capacitor SMD 0402")
		(tags "capacitor SMD 0402")
		(property "Reference" "C179"
			(at -3.69 0.45 180)
			(layer "F.SilkS")
			(effects
				(font
					(size 0.7 0.7)
					(thickness 0.15)
				)
				(justify left bottom)
			)
		)
		(property "Value" "C_100n_0402"
			(at -1.022927 2.155213 0)
			(layer "F.Fab")
			(effects
				(font
					(size 0.7 0.7)
					(thickness 0.15)
				)
				(justify left bottom)
			)
		)
		(property "Datasheet" "https://www.murata.com/products/productdetail?partno=GRM155R61H104KE14%23"
			(at 0 0 0)
			(layer "F.Fab")
			(hide yes)
			(effects
				(font
					(size 1.27 1.27)
					(thickness 0.15)
				)
			)
		)
		(property "Author" "Antmicro"
			(at 0 0 0)
			(layer "F.Fab")
			(hide yes)
			(effects
				(font
					(size 1 1)
					(thickness 0.15)
				)
			)
		)
		(property "Dielectric" "X5R"
			(at 0 0 0)
			(layer "F.Fab")
			(hide yes)
			(effects
				(font
					(size 1 1)
					(thickness 0.15)
				)
			)
		)
		(property "License" "Apache-2.0"
			(at 0 0 0)
			(layer "F.Fab")
			(hide yes)
			(effects
				(font
					(size 1 1)
					(thickness 0.15)
				)
			)
		)
		(property "MPN" "GRM155R61H104KE14D"
			(at 0 0 0)
			(layer "F.Fab")
			(hide yes)
			(effects
				(font
					(size 1 1)
					(thickness 0.15)
				)
			)
		)
		(property "Manufacturer" "Murata"
			(at 0 0 0)
			(layer "F.Fab")
			(hide yes)
			(effects
				(font
					(size 1 1)
					(thickness 0.15)
				)
			)
		)
		(property "Public" "False"
			(at 0 0 0)
			(layer "F.Fab")
			(hide yes)
			(effects
				(font
					(size 1 1)
					(thickness 0.15)
				)
			)
		)
		(property "Val" "100n"
			(at 0 0 0)
			(layer "F.Fab")
			(hide yes)
			(effects
				(font
					(size 1 1)
					(thickness 0.15)
				)
			)
		)
		(property "Voltage" "50V"
			(at 0 0 0)
			(layer "F.Fab")
			(hide yes)
			(effects
				(font
					(size 1 1)
					(thickness 0.15)
				)
			)
		)
		(sheetname "KR to SFI #2")
		(sheetfile "kr_sfi.kicad_sch")
		(attr smd)
		(fp_rect
			(start -0.925 -0.47)
			(end 0.925 0.47)
			(stroke
				(width 0.05)
				(type default)
			)
			(fill no)
			(layer "F.CrtYd")
		)
		(fp_line
			(start -0.494 -0.25)
			(end 0.504 -0.25)
			(stroke
				(width 0.15)
				(type solid)
			)
			(layer "F.Fab")
		)
		(fp_line
			(start -0.494 0.248)
			(end -0.494 -0.25)
			(stroke
				(width 0.15)
				(type solid)
			)
			(layer "F.Fab")
		)
		(fp_line
			(start 0.504 -0.25)
			(end 0.504 0.248)
			(stroke
				(width 0.15)
				(type solid)
			)
			(layer "F.Fab")
		)
		(fp_line
			(start 0.504 0.248)
			(end -0.494 0.248)
			(stroke
				(width 0.15)
				(type solid)
			)
			(layer "F.Fab")
		)
		(pad "1" smd roundrect
			(at -0.48 0)
			(size 0.59 0.64)
			(layers "F.Cu" "F.Mask" "F.Paste")
			(roundrect_rratio 0.25)
			(net 115 "/2xSFP+/KR to SFI #2/CLK+")
			(pintype "passive")
			(teardrops
				(best_length_ratio 0.2)
				(max_length 1)
				(best_width_ratio 0.9)
				(max_width 2)
				(curved_edges yes)
				(filter_ratio 0.9)
				(enabled yes)
				(allow_two_segments yes)
				(prefer_zone_connections yes)
			)
		)
		(pad "2" smd roundrect
			(at 0.48 0)
			(size 0.59 0.64)
			(layers "F.Cu" "F.Mask" "F.Paste")
			(roundrect_rratio 0.25)
			(net 118 "/2xSFP+/KR to SFI #2/REFCLK-")
			(pintype "passive")
			(teardrops
				(best_length_ratio 0.2)
				(max_length 1)
				(best_width_ratio 0.9)
				(max_width 2)
				(curved_edges yes)
				(filter_ratio 0.9)
				(enabled yes)
				(allow_two_segments yes)
				(prefer_zone_connections yes)
			)
		)
	)
	(footprint "antmicro-footprints:C_0402_1005Metric"
		(layer "F.Cu")
		(at 194.340683 136.693926 -45)
		(descr "Capacitor SMD 0402")
		(tags "capacitor SMD 0402")
		(property "Reference" "C133"
			(at 3.864616 -0.431761 135)
			(layer "F.SilkS")
			(effects
				(font
					(size 0.7 0.7)
					(thickness 0.15)
				)
				(justify right top)
			)
		)
		(property "Value" "C_100n_0402"
			(at -1.022927 2.155213 135)
			(layer "F.Fab")
			(effects
				(font
					(size 0.7 0.7)
					(thickness 0.15)
				)
				(justify right top)
			)
		)
		(property "Datasheet" "https://www.murata.com/products/productdetail?partno=GRM155R61H104KE14%23"
			(at 0 0 135)
			(layer "B.Fab")
			(hide yes)
			(effects
				(font
					(size 1.27 1.27)
					(thickness 0.15)
				)
				(justify mirror)
			)
		)
		(property "Author" "Antmicro"
			(at 52.668 -325.634001 45)
			(layer "F.Fab")
			(hide yes)
			(effects
				(font
					(size 1 1)
					(thickness 0.15)
				)
			)
		)
		(property "Dielectric" "X5R"
			(at 52.668 -325.634001 45)
			(layer "F.Fab")
			(hide yes)
			(effects
				(font
					(size 1 1)
					(thickness 0.15)
				)
			)
		)
		(property "License" "Apache-2.0"
			(at 52.668 -325.634001 45)
			(layer "F.Fab")
			(hide yes)
			(effects
				(font
					(size 1 1)
					(thickness 0.15)
				)
			)
		)
		(property "MPN" "GRM155R61H104KE14D"
			(at 52.668 -325.634001 45)
			(layer "F.Fab")
			(hide yes)
			(effects
				(font
					(size 1 1)
					(thickness 0.15)
				)
			)
		)
		(property "Manufacturer" "Murata"
			(at 52.668 -325.634001 45)
			(layer "F.Fab")
			(hide yes)
			(effects
				(font
					(size 1 1)
					(thickness 0.15)
				)
			)
		)
		(property "Public" "False"
			(at 52.668 -325.634001 45)
			(layer "F.Fab")
			(hide yes)
			(effects
				(font
					(size 1 1)
					(thickness 0.15)
				)
			)
		)
		(property "Val" "100n"
			(at 52.668 -325.634001 45)
			(layer "F.Fab")
			(hide yes)
			(effects
				(font
					(size 1 1)
					(thickness 0.15)
				)
			)
		)
		(property "Voltage" "50V"
			(at 52.668 -325.634001 45)
			(layer "F.Fab")
			(hide yes)
			(effects
				(font
					(size 1 1)
					(thickness 0.15)
				)
			)
		)
		(sheetname "PCIe redriver")
		(sheetfile "pcie_redriver.kicad_sch")
		(attr smd)
		(fp_poly
			(pts
				(xy -0.925 -0.47) (xy 0.925 -0.47) (xy 0.925 0.47) (xy -0.925 0.47)
			)
			(stroke
				(width 0.05)
				(type default)
			)
			(fill no)
			(layer "F.CrtYd")
		)
		(fp_line
			(start -0.494 0.248)
			(end -0.494 -0.25)
			(stroke
				(width 0.15)
				(type solid)
			)
			(layer "F.Fab")
		)
		(fp_line
			(start -0.494 -0.25)
			(end 0.504 -0.25)
			(stroke
				(width 0.15)
				(type solid)
			)
			(layer "F.Fab")
		)
		(fp_line
			(start 0.504 0.248)
			(end -0.494 0.248)
			(stroke
				(width 0.15)
				(type solid)
			)
			(layer "F.Fab")
		)
		(fp_line
			(start 0.504 -0.25)
			(end 0.504 0.248)
			(stroke
				(width 0.15)
				(type solid)
			)
			(layer "F.Fab")
		)
		(pad "1" smd roundrect
			(at -0.48 0 315)
			(size 0.59 0.64)
			(layers "F.Cu" "F.Mask" "F.Paste")
			(roundrect_rratio 0.25)
			(net 1 "GND")
			(pintype "passive")
			(teardrops
				(best_length_ratio 0.2)
				(max_length 1)
				(best_width_ratio 0.9)
				(max_width 2)
				(curved_edges yes)
				(filter_ratio 0.9)
				(enabled yes)
				(allow_two_segments yes)
				(prefer_zone_connections yes)
			)
		)
		(pad "2" smd roundrect
			(at 0.48 0 315)
			(size 0.59 0.64)
			(layers "F.Cu" "F.Mask" "F.Paste")
			(roundrect_rratio 0.25)
			(net 2 "+3V3")
			(pintype "passive")
			(teardrops
				(best_length_ratio 0.2)
				(max_length 1)
				(best_width_ratio 0.9)
				(max_width 2)
				(curved_edges yes)
				(filter_ratio 0.9)
				(enabled yes)
				(allow_two_segments yes)
				(prefer_zone_connections yes)
			)
		)
	)
	(footprint "antmicro-footprints:R_0402_1005Metric"
		(layer "F.Cu")
		(at 122.05 87.06)
		(descr "Resistor SMD 0402")
		(tags "resistor SMD 0402")
		(property "Reference" "R18"
			(at 0.75 0.45 0)
			(layer "F.SilkS")
			(effects
				(font
					(size 0.7 0.7)
					(thickness 0.15)
				)
				(justify left bottom)
			)
		)
		(property "Value" "R_10k_0402"
			(at -1.011843 1.772047 0)
			(layer "F.Fab")
			(effects
				(font
					(size 0.7 0.7)
					(thickness 0.15)
				)
				(justify left bottom)
			)
		)
		(property "Datasheet" "https://www.bourns.com/docs/product-datasheets/cr.pdf"
			(at 0 0 0)
			(layer "F.Fab")
			(hide yes)
			(effects
				(font
					(size 1.27 1.27)
					(thickness 0.15)
				)
			)
		)
		(property "Author" "Antmicro"
			(at 0 0 0)
			(layer "F.Fab")
			(hide yes)
			(effects
				(font
					(size 1 1)
					(thickness 0.15)
				)
			)
		)
		(property "License" "Apache-2.0"
			(at 0 0 0)
			(layer "F.Fab")
			(hide yes)
			(effects
				(font
					(size 1 1)
					(thickness 0.15)
				)
			)
		)
		(property "MPN" "CR0402-FX-1002GLF"
			(at 0 0 0)
			(layer "F.Fab")
			(hide yes)
			(effects
				(font
					(size 1 1)
					(thickness 0.15)
				)
			)
		)
		(property "Manufacturer" "Bourns"
			(at 0 0 0)
			(layer "F.Fab")
			(hide yes)
			(effects
				(font
					(size 1 1)
					(thickness 0.15)
				)
			)
		)
		(property "Public" "False"
			(at 0 0 0)
			(layer "F.Fab")
			(hide yes)
			(effects
				(font
					(size 1 1)
					(thickness 0.15)
				)
			)
		)
		(property "Tolerance" "1%"
			(at 0 0 0)
			(layer "F.Fab")
			(hide yes)
			(effects
				(font
					(size 1 1)
					(thickness 0.15)
				)
			)
		)
		(property "Val" "10k"
			(at 0 0 0)
			(layer "F.Fab")
			(hide yes)
			(effects
				(font
					(size 1 1)
					(thickness 0.15)
				)
			)
		)
		(sheetname "2xUSB3.0+RJ45")
		(sheetfile "usb3+rj45.kicad_sch")
		(attr smd dnp)
		(fp_rect
			(start -0.925 -0.47)
			(end 0.925 0.47)
			(stroke
				(width 0.05)
				(type default)
			)
			(fill no)
			(layer "F.CrtYd")
		)
		(fp_rect
			(start -0.5 -0.25)
			(end 0.5 0.25)
			(stroke
				(width 0.15)
				(type solid)
			)
			(fill no)
			(layer "F.Fab")
		)
		(pad "1" smd roundrect
			(at -0.48 0)
			(size 0.59 0.64)
			(layers "F.Cu" "F.Mask" "F.Paste")
			(roundrect_rratio 0.25)
			(net 553 "/2xUSB3.0+RJ45/FLG_1B")
			(pintype "passive")
			(teardrops
				(best_length_ratio 0.2)
				(max_length 1)
				(best_width_ratio 0.9)
				(max_width 2)
				(curved_edges yes)
				(filter_ratio 0.9)
				(enabled yes)
				(allow_two_segments yes)
				(prefer_zone_connections yes)
			)
		)
		(pad "2" smd roundrect
			(at 0.48 0)
			(size 0.59 0.64)
			(layers "F.Cu" "F.Mask" "F.Paste")
			(roundrect_rratio 0.25)
			(net 2 "+3V3")
			(pintype "passive")
			(teardrops
				(best_length_ratio 0.2)
				(max_length 1)
				(best_width_ratio 0.9)
				(max_width 2)
				(curved_edges yes)
				(filter_ratio 0.9)
				(enabled yes)
				(allow_two_segments yes)
				(prefer_zone_connections yes)
			)
		)
	)
)
